FILE_TYPE = CONNECTIVITY;
{Allegro Design Entry HDL 17.2-2016 S081 (4005846) 1/11/2022}
"PAGE_NUMBER" = 231;
0"NC";
1"P3V3_AUX\g";
2"P3V3_AUX\g"$PHYS_NET_NAME"P3V3_AUX"CDS_PHYS_NET_NAME"P3V3_AUX"VOLTAGE"3.3"$PHYS_NET_NAME"P3V3_AUX"CDS_PHYS_NET_NAME"P3V3_AUX"VOLTAGE"3.3"$PHYS_NET_NAME"P3V3_AUX"CDS_PHYS_NET_NAME"P3V3_AUX"VOLTAGE"3.3";
3"P3V3_AUX\g";
4"GND\g";
5"GND\g";
6"GND\g";
7"GND\g";
8"GND\g";
9"GND\g";
10"PD_MB_FRU_WP";
11"SMB_FRU_3V3AUX_SDA"CDS_PHYS_NET_NAME"SMB_PCIE_3V3AUX_SDA_R"CDS_PHYS_NET_NAME"SMB_PCIE_3V3AUX_SCL";
12"MB_FRU_ADDR0"CDS_PHYS_NET_NAME"PCA9548_PCIE_ADDR2";
13"MB_FRU_ADDR1"CDS_PHYS_NET_NAME"PCA9548_PCIE_ADDR2";
14"MB_FRU_ADDR2"CDS_PHYS_NET_NAME"PCA9548_PCIE_ADDR2";
15"SMB_FRU_3V3AUX_SCL"CDS_PHYS_NET_NAME"SMB_PCIE_3V3AUX_SCL_R"CDS_PHYS_NET_NAME"SMB_PCIE_3V3AUX_SDA";
%"M24128BWMN6TP"
"1","(100,2250)","0","pure_quanta","I35";
;
PART_NUMBER"AKE30Z00613"
MATERIAL"IC"
VALUE"M24128-BWMN6TP"
PART_TYPE"SMLF"
$LOCATION"U64"
CDS_LMAN_SYM_OUTLINE"-150,125,150,-125"
NEEDS_NO_SIZE"TRUE"
CDS_LIB"pure_quanta"
CDS_LOCATION"U64"
$SEC"1"
CDS_SEC"1";
"E0"
$PN"1"12;
"E1"
$PN"2"13;
"E2"
$PN"3"14;
"VSS"
$PN"4"7;
"SDA"
$PN"5"11;
"SCL"
$PN"6"15;
"WC# \B"
$PN"7"10;
"VCC"
$PN"8"2;
%"Q_RES"
"2","(2125,2550)","0","pure_quanta","I45";
;
PART_NUMBER"CS31002FB08"
PACK_TYPE"0402LF"
MATERIAL"EMPTY"
WATTAGE"1/16W"
VALUE"10K"
TOLERANCE"1%"
$LOCATION"R717"
CDS_LIB"pure_quanta"
CDS_LOCATION"R717"
$SEC"1"
CDS_SEC"1";
"A"
$PN"1"1;
"B"
$PN"2"13;
%"Q_RES"
"2","(1850,2550)","0","pure_quanta","I47";
;
PART_NUMBER"CS31002FB08"
WATTAGE"1/16W"
PACK_TYPE"0402LF"
VALUE"10K"
TOLERANCE"1%"
MATERIAL"EMPTY"
$LOCATION"R713"
CDS_LIB"pure_quanta"
CDS_LOCATION"R713"
$SEC"1"
CDS_SEC"1";
"A"
$PN"1"1;
"B"
$PN"2"14;
%"UNIVERSAL_GND"
"1","(2400,1775)","0","logical_power","I49";
;
CDS_LIB"logical_power"
HDL_POWER"GND"
ROOM"IO_SLOT";
"A"4;
%"Q_RES"
"2","(2125,2000)","0","pure_quanta","I50";
;
PART_NUMBER"CS21002FB06"
WATTAGE"1/16W"
MATERIAL"CHIP"
VALUE"1K"
TOLERANCE"1%"
PACK_TYPE"0402LF"
$LOCATION"R718"
CDS_LIB"pure_quanta"
CDS_LOCATION"R718"
$SEC"1"
CDS_SEC"1";
"A"
$PN"1"13;
"B"
$PN"2"5;
%"UNIVERSAL_GND"
"1","(2125,1775)","0","logical_power","I51";
;
CDS_LIB"logical_power"
HDL_POWER"GND"
ROOM"IO_SLOT";
"A"5;
%"Q_RES"
"2","(1850,2000)","0","pure_quanta","I52";
;
PART_NUMBER"CS21002FB06"
VALUE"1K"
PACK_TYPE"0402LF"
MATERIAL"CHIP"
WATTAGE"1/16W"
TOLERANCE"1%"
$LOCATION"R714"
CDS_LIB"pure_quanta"
CDS_LOCATION"R714"
$SEC"1"
CDS_SEC"1";
"A"
$PN"1"14;
"B"
$PN"2"6;
%"UNIVERSAL_GND"
"1","(1850,1775)","0","logical_power","I53";
;
CDS_LIB"logical_power"
HDL_POWER"GND"
ROOM"IO_SLOT";
"A"6;
%"UNIVERSAL_POWER"
"1","(-425,2900)","0","logical_power","I54";
;
HDL_POWER"P3V3_AUX"
CDS_LIB"logical_power";
"A"2;
%"Q_CAP"
"1","(-425,2575)","2","pure_quanta","I55";
;
PART_NUMBER"CH4104K1B00"
MATERIAL"X7R"
TOLERANCE"10%"
VOLTAGE"25V"
VALUE"0.1UF"
PACK_TYPE"0402"
$LOCATION"C629"
CDS_LIB"pure_quanta"
CDS_LOCATION"C629"
$SEC"1"
CDS_SEC"1";
"B"
$PN"2"8;
"A"
$PN"1"2;
%"UNIVERSAL_GND"
"1","(-425,2350)","0","logical_power","I56";
;
CDS_LIB"logical_power"
HDL_POWER"GND";
"A"8;
%"Q_RES"
"2","(-975,1950)","0","pure_quanta","I57";
;
PART_NUMBER"CS21002FB06"
MATERIAL"CHIP"
VALUE"1K"
WATTAGE"1/16W"
TOLERANCE"1%"
PACK_TYPE"0402LF"
$LOCATION"R710"
CDS_LIB"pure_quanta"
CDS_LOCATION"R710"
$SEC"1"
CDS_SEC"1";
"A"
$PN"1"10;
"B"
$PN"2"9;
%"UNIVERSAL_GND"
"1","(-975,1725)","0","logical_power","I58";
;
CDS_LIB"logical_power"
HDL_POWER"GND";
"A"9;
%"UNIVERSAL_GND"
"1","(550,1925)","0","logical_power","I59";
;
CDS_LIB"logical_power"
HDL_POWER"GND";
"A"7;
%"UNIVERSAL_POWER"
"1","(1850,2925)","0","logical_power","I60";
;
HDL_POWER"P3V3_AUX"
CDS_LIB"logical_power";
"A"1;
%"Q_RES"
"2","(2400,2000)","0","pure_quanta","I61";
;
PART_NUMBER"CS21002FB06"
TOLERANCE"1%"
VALUE"1K"
PACK_TYPE"0402LF"
MATERIAL"EMPTY"
WATTAGE"1/16W"
$LOCATION"R722"
CDS_LIB"pure_quanta"
CDS_LOCATION"R722"
$SEC"1"
CDS_SEC"1";
"A"
$PN"1"12;
"B"
$PN"2"4;
%"Q_RES"
"2","(2400,2550)","0","pure_quanta","I62";
;
PART_NUMBER"CS31002FB08"
TOLERANCE"1%"
VALUE"10K"
WATTAGE"1/16W"
PACK_TYPE"0402LF"
MATERIAL"CHIP"
$LOCATION"R721"
CDS_LIB"pure_quanta"
CDS_LOCATION"R721"
$SEC"1"
CDS_SEC"1";
"A"
$PN"1"1;
"B"
$PN"2"12;
%"Q_RES"
"2","(-1575,2525)","0","pure_quanta","I93";
;
PART_NUMBER"CS24702JB10"
PACK_TYPE"0402LF"
TOLERANCE"5%"
MATERIAL"EMPTY"
WATTAGE"1/16W"
VALUE"4.7K"
$LOCATION"R1332"
CDS_LIB"pure_quanta"
CDS_LOCATION"R1332"
$SEC"1"
CDS_SEC"1";
"A"
$PN"1"3;
"B"
$PN"2"11;
%"Q_RES"
"2","(-1675,2525)","2","pure_quanta","I95";
;
PART_NUMBER"CS24702JB10"
TOLERANCE"5%"
WATTAGE"1/16W"
MATERIAL"EMPTY"
PACK_TYPE"0402LF"
VALUE"4.7K"
$LOCATION"R1331"
CDS_LIB"pure_quanta"
CDS_LOCATION"R1331"
$SEC"1"
CDS_SEC"1";
"A"
$PN"1"3;
"B"
$PN"2"15;
%"UNIVERSAL_POWER"
"1","(-1675,2825)","0","logical_power","I96";
;
HDL_POWER"P3V3_AUX"
CDS_LIB"logical_power";
"A"3;
END.
